# T6G (Grand Teton) — schematic netlist excerpt (pin names and nets, part order shuffled) for the footprints in the layout excerpt that follows; sources: Cadence DE-HDL packaged netlist, KiCad conversion of 04192023_DAF0TMB3IC0_F0TG_MB_C_brd_V02_OCP.brd

R1284  Q_RES  10 1% CHIP  pkg 0402LF  page 357 : A = P12V_OCP_SFF ; B = VSENSE_P12V_INA230_6_INP
R3680  Q_RES  0 5% CHIP  pkg 0402LF  page 257 : A = P12V_AUX_ADC ; B = P12V_AUX_ADC_TIC
C1333  Q_CAP  10UF 16V 10% X6S  pkg C0805  page 188 : A = P3V3_AUX ; B = GND

(kicad_pcb
	(version 20260206)
	(generator "pcbnew")
	(generator_version "10.0")
	(general
		(thickness 1.6)
		(legacy_teardrops no)
	)
	(paper "A4")
	(title_block
		(title "04192023_DAF0TMB3IC0_F0TG_MB_C_brd_V02_OCP.brd")
		(comment 1 "Grand Teton / footprints 4470-4472 of 8354")
	)
	(layers
		(0 "F.Cu" signal "TOP")
		(4 "In1.Cu" signal "GND")
		(6 "In2.Cu" signal "IN1")
		(8 "In3.Cu" signal "GND1")
		(10 "In4.Cu" signal "IN2")
		(12 "In5.Cu" signal "GND2")
		(14 "In6.Cu" signal "IN3")
		(16 "In7.Cu" signal "GND3")
		(18 "In8.Cu" signal "VCC")
		(20 "In9.Cu" signal "VCC1")
		(22 "In10.Cu" signal "GND4")
		(24 "In11.Cu" signal "IN4")
		(26 "In12.Cu" signal "GND5")
		(28 "In13.Cu" signal "IN5")
		(30 "In14.Cu" signal "GND6")
		(32 "In15.Cu" signal "IN6")
		(34 "In16.Cu" signal "GND7")
		(2 "B.Cu" signal "BOTTOM")
		(9 "F.Adhes" user "F.Adhesive")
		(11 "B.Adhes" user "B.Adhesive")
		(13 "F.Paste" user "Package Geometry/Pastemask Top")
		(15 "B.Paste" user "Package Geometry/Pastemask Bottom")
		(5 "F.SilkS" user "Ref Des/Silkscreen Top")
		(7 "B.SilkS" user "Ref Des/Silkscreen Bottom")
		(1 "F.Mask" user "Board Geometry/Soldermask Top")
		(3 "B.Mask" user "Board Geometry/Soldermask Bottom")
		(17 "Dwgs.User" user "User.Drawings")
		(19 "Cmts.User" user "User.Comments")
		(21 "Eco1.User" user "User.Eco1")
		(23 "Eco2.User" user "User.Eco2")
		(25 "Edge.Cuts" user "Board Geometry/Outline")
		(27 "Margin" user)
		(31 "F.CrtYd" user "Package Geometry/Place Bound Top")
		(29 "B.CrtYd" user "Package Geometry/Place Bound Bottom")
		(35 "F.Fab" user "Ref Des/Assembly Top")
		(33 "B.Fab" user "Ref Des/Assembly Bottom")
	)
	(footprint ""
		(layer "F.Cu")
		(at 448.32778 -65.792858 -90)
		(property "Reference" "C1333"
			(at 0 0 270)
			(layer "F.SilkS")
			(hide yes)
			(effects
				(font
					(size 1.27 1.27)
				)
			)
		)
		(property "Value" ""
			(at 0 0 270)
			(layer "F.Fab")
			(effects
				(font
					(size 1.27 1.27)
				)
			)
		)
		(duplicate_pad_numbers_are_jumpers no)
		(fp_line
			(start -1.524 0.762)
			(end -1.524 -0.762)
			(stroke
				(width 0.1524)
				(type default)
			)
			(layer "F.SilkS")
		)
		(fp_line
			(start 1.524 0.762)
			(end -1.524 0.762)
			(stroke
				(width 0.1524)
				(type default)
			)
			(layer "F.SilkS")
		)
		(fp_line
			(start -1.524 -0.762)
			(end 1.524 -0.762)
			(stroke
				(width 0.1524)
				(type default)
			)
			(layer "F.SilkS")
		)
		(fp_line
			(start 1.524 -0.762)
			(end 1.524 0.762)
			(stroke
				(width 0.1524)
				(type default)
			)
			(layer "F.SilkS")
		)
		(fp_line
			(start -1.1049 0.724916)
			(end 1.1049 0.724916)
			(stroke
				(width 0.1)
				(type default)
			)
			(layer "F.Fab")
		)
		(fp_line
			(start 1.1049 0.724916)
			(end 1.1049 -0.724916)
			(stroke
				(width 0.1)
				(type default)
			)
			(layer "F.Fab")
		)
		(fp_line
			(start -1.1049 -0.724916)
			(end -1.1049 0.724916)
			(stroke
				(width 0.1)
				(type default)
			)
			(layer "F.Fab")
		)
		(fp_line
			(start 1.1049 -0.724916)
			(end -1.1049 -0.724916)
			(stroke
				(width 0.1)
				(type default)
			)
			(layer "F.Fab")
		)
		(pad "1" smd rect
			(at -0.889 0 90)
			(size 1.016 1.27)
			(layers "F.Cu" "F.Mask" "F.Paste")
			(net "P3V3_AUX")
		)
		(pad "2" smd rect
			(at 0.889 0 90)
			(size 1.016 1.27)
			(layers "F.Cu" "F.Mask" "F.Paste")
			(net "GND")
		)
	)
	(footprint ""
		(layer "F.Cu")
		(at 322.837048 -46.986698 180)
		(property "Reference" "R3680"
			(at 0 0 180)
			(layer "F.SilkS")
			(hide yes)
			(effects
				(font
					(size 1.27 1.27)
				)
			)
		)
		(property "Value" ""
			(at 0 0 180)
			(layer "F.Fab")
			(effects
				(font
					(size 1.27 1.27)
				)
			)
		)
		(duplicate_pad_numbers_are_jumpers no)
		(fp_line
			(start 0.7874 0.4064)
			(end -0.7874 0.4064)
			(stroke
				(width 0.1524)
				(type default)
			)
			(layer "F.SilkS")
		)
		(fp_line
			(start 0.7874 -0.4064)
			(end 0.7874 0.4064)
			(stroke
				(width 0.1524)
				(type default)
			)
			(layer "F.SilkS")
		)
		(fp_line
			(start -0.7874 0.4064)
			(end -0.7874 -0.4064)
			(stroke
				(width 0.1524)
				(type default)
			)
			(layer "F.SilkS")
		)
		(fp_line
			(start -0.7874 -0.4064)
			(end 0.7874 -0.4064)
			(stroke
				(width 0.1524)
				(type default)
			)
			(layer "F.SilkS")
		)
		(fp_line
			(start 0.67945 0.3048)
			(end 0.120396 0.3048)
			(stroke
				(width 0.1)
				(type default)
			)
			(layer "F.Fab")
		)
		(fp_line
			(start 0.67945 -0.3048)
			(end 0.67945 0.3048)
			(stroke
				(width 0.1)
				(type default)
			)
			(layer "F.Fab")
		)
		(fp_line
			(start 0.12065 -0.2794)
			(end 0.12065 -0.3048)
			(stroke
				(width 0.1)
				(type default)
			)
			(layer "F.Fab")
		)
		(fp_line
			(start 0.12065 -0.3048)
			(end 0.67945 -0.3048)
			(stroke
				(width 0.1)
				(type default)
			)
			(layer "F.Fab")
		)
		(fp_line
			(start 0.120396 0.3048)
			(end 0.120396 0.2794)
			(stroke
				(width 0.1)
				(type default)
			)
			(layer "F.Fab")
		)
		(fp_line
			(start 0.120396 0.2794)
			(end -0.12065 0.2794)
			(stroke
				(width 0.1)
				(type default)
			)
			(layer "F.Fab")
		)
		(fp_line
			(start -0.12065 0.3048)
			(end -0.67945 0.3048)
			(stroke
				(width 0.1)
				(type default)
			)
			(layer "F.Fab")
		)
		(fp_line
			(start -0.12065 0.2794)
			(end -0.12065 0.3048)
			(stroke
				(width 0.1)
				(type default)
			)
			(layer "F.Fab")
		)
		(fp_line
			(start -0.12065 -0.2794)
			(end 0.12065 -0.2794)
			(stroke
				(width 0.1)
				(type default)
			)
			(layer "F.Fab")
		)
		(fp_line
			(start -0.12065 -0.305054)
			(end -0.12065 -0.2794)
			(stroke
				(width 0.1)
				(type default)
			)
			(layer "F.Fab")
		)
		(fp_line
			(start -0.67945 0.3048)
			(end -0.67945 -0.305054)
			(stroke
				(width 0.1)
				(type default)
			)
			(layer "F.Fab")
		)
		(fp_line
			(start -0.67945 -0.305054)
			(end -0.12065 -0.305054)
			(stroke
				(width 0.1)
				(type default)
			)
			(layer "F.Fab")
		)
		(pad "1" smd rect
			(at -0.40005 0)
			(size 0.4572 0.508)
			(layers "F.Cu" "F.Mask" "F.Paste")
			(net "P12V_AUX_ADC")
		)
		(pad "2" smd rect
			(at 0.40005 0)
			(size 0.4572 0.508)
			(layers "F.Cu" "F.Mask" "F.Paste")
			(net "P12V_AUX_ADC_TIC")
		)
	)
	(footprint ""
		(layer "F.Cu")
		(at 443.308486 -21.676106 180)
		(property "Reference" "R1284"
			(at 0 0 180)
			(layer "F.SilkS")
			(hide yes)
			(effects
				(font
					(size 1.27 1.27)
				)
			)
		)
		(property "Value" ""
			(at 0 0 180)
			(layer "F.Fab")
			(effects
				(font
					(size 1.27 1.27)
				)
			)
		)
		(duplicate_pad_numbers_are_jumpers no)
		(fp_line
			(start 0.7874 0.4064)
			(end -0.7874 0.4064)
			(stroke
				(width 0.1524)
				(type default)
			)
			(layer "F.SilkS")
		)
		(fp_line
			(start 0.7874 -0.4064)
			(end 0.7874 0.4064)
			(stroke
				(width 0.1524)
				(type default)
			)
			(layer "F.SilkS")
		)
		(fp_line
			(start -0.7874 0.4064)
			(end -0.7874 -0.4064)
			(stroke
				(width 0.1524)
				(type default)
			)
			(layer "F.SilkS")
		)
		(fp_line
			(start -0.7874 -0.4064)
			(end 0.7874 -0.4064)
			(stroke
				(width 0.1524)
				(type default)
			)
			(layer "F.SilkS")
		)
		(fp_line
			(start 0.67945 0.3048)
			(end 0.120396 0.3048)
			(stroke
				(width 0.1)
				(type default)
			)
			(layer "F.Fab")
		)
		(fp_line
			(start 0.67945 -0.3048)
			(end 0.67945 0.3048)
			(stroke
				(width 0.1)
				(type default)
			)
			(layer "F.Fab")
		)
		(fp_line
			(start 0.12065 -0.2794)
			(end 0.12065 -0.3048)
			(stroke
				(width 0.1)
				(type default)
			)
			(layer "F.Fab")
		)
		(fp_line
			(start 0.12065 -0.3048)
			(end 0.67945 -0.3048)
			(stroke
				(width 0.1)
				(type default)
			)
			(layer "F.Fab")
		)
		(fp_line
			(start 0.120396 0.3048)
			(end 0.120396 0.2794)
			(stroke
				(width 0.1)
				(type default)
			)
			(layer "F.Fab")
		)
		(fp_line
			(start 0.120396 0.2794)
			(end -0.12065 0.2794)
			(stroke
				(width 0.1)
				(type default)
			)
			(layer "F.Fab")
		)
		(fp_line
			(start -0.12065 0.3048)
			(end -0.67945 0.3048)
			(stroke
				(width 0.1)
				(type default)
			)
			(layer "F.Fab")
		)
		(fp_line
			(start -0.12065 0.2794)
			(end -0.12065 0.3048)
			(stroke
				(width 0.1)
				(type default)
			)
			(layer "F.Fab")
		)
		(fp_line
			(start -0.12065 -0.2794)
			(end 0.12065 -0.2794)
			(stroke
				(width 0.1)
				(type default)
			)
			(layer "F.Fab")
		)
		(fp_line
			(start -0.12065 -0.305054)
			(end -0.12065 -0.2794)
			(stroke
				(width 0.1)
				(type default)
			)
			(layer "F.Fab")
		)
		(fp_line
			(start -0.67945 0.3048)
			(end -0.67945 -0.305054)
			(stroke
				(width 0.1)
				(type default)
			)
			(layer "F.Fab")
		)
		(fp_line
			(start -0.67945 -0.305054)
			(end -0.12065 -0.305054)
			(stroke
				(width 0.1)
				(type default)
			)
			(layer "F.Fab")
		)
		(pad "1" smd circle
			(at -0.40005 0 180)
			(size 0 0)
			(layers "F.Cu" "F.Mask" "F.Paste")
			(net "P12V_OCP_SFF")
		)
		(pad "2" smd circle
			(at 0.40005 0 180)
			(size 0 0)
			(layers "F.Cu" "F.Mask" "F.Paste")
			(net "VSENSE_P12V_INA230_6_INP")
		)
	)
)
